FILE_TYPE = CONNECTIVITY;
{Allegro Design Entry HDL 17.4-2019 S026 (4007227) 1/17/2022}
"PAGE_NUMBER" = 439;
0"NC";
1"P5E_CPU1_P0_TX_BUF_DN<7:0>";
2"P5E_CPU1_P0_TX_BUF_C_DN<7:0>";
3"P5E_CPU1_P0_TX_BUF_DP<7:0>";
4"P5E_CPU1_P0_TX_BUF_C_DP<7:0>";
5"P5E_CPU1_P0_TX_BUF_DN<15:8>";
6"P5E_CPU1_P0_TX_BUF_DP<15:8>";
7"P5E_CPU1_P0_TX_BUF_C_DN<15:8>";
8"P5E_CPU1_P0_TX_BUF_C_DP<15:8>";
9"P5E_CPU1_P0_TX_BUF_DN<15:8>";
10"P5E_CPU1_P0_TX_BUF_DP<15:8>";
11"P5E_CPU1_P0_TX_BUF_DP<7:0>";
12"P5E_CPU1_P0_TX_BUF_DN<7:0>";
13"P5E_CPU1_P0_TX_BUF_DN<13>";
14"P5E_CPU1_P0_TX_BUF_DN<12>";
15"P5E_CPU1_P0_TX_BUF_DN<0>";
16"P5E_CPU1_P0_TX_BUF_DP<1>";
17"P5E_CPU1_P0_TX_BUF_DP<2>";
18"P5E_CPU1_P0_TX_BUF_DN<2>";
19"P5E_CPU1_P0_TX_BUF_DP<4>";
20"P5E_CPU1_P0_TX_BUF_DN<4>";
21"P5E_CPU1_P0_TX_BUF_DN<5>";
22"P5E_CPU1_P0_TX_BUF_DP<11>";
23"P5E_CPU1_P0_TX_BUF_DP<12>";
24"P5E_CPU1_P0_TX_BUF_DP<10>";
25"P5E_CPU1_P0_TX_BUF_DP<13>";
26"P5E_CPU1_P0_TX_BUF_DN<10>";
27"P5E_CPU1_P0_TX_BUF_DP<6>";
28"P5E_CPU1_P0_TX_BUF_DN<11>";
29"P5E_CPU1_P0_TX_BUF_DP<8>";
30"P5E_CPU1_P0_TX_BUF_DN<8>";
31"P5E_CPU1_P0_TX_BUF_DP<0>";
32"P5E_CPU1_P0_TX_BUF_DN<1>";
33"P5E_CPU1_P0_TX_BUF_DN<3>";
34"P5E_CPU1_P0_TX_BUF_DP<3>";
35"P5E_CPU1_P0_TX_BUF_DP<5>";
36"P5E_CPU1_P0_TX_BUF_DN<6>";
37"P5E_CPU1_P0_TX_BUF_DN<7>";
38"P5E_CPU1_P0_TX_BUF_DP<7>";
39"P5E_CPU1_P0_TX_BUF_DN<9>";
40"P5E_CPU1_P0_TX_BUF_DP<9>";
41"P5E_CPU1_P0_TX_BUF_DP<15>";
42"P5E_CPU1_P0_TX_BUF_DN<14>";
43"P5E_CPU1_P0_TX_BUF_DP<14>";
44"P5E_CPU1_P0_TX_BUF_DN<15>";
45"P5E_CPU1_P0_TX_BUF_C_DP<12>";
46"P5E_CPU1_P0_TX_BUF_C_DP<8>";
47"P5E_CPU1_P0_TX_BUF_DP<8>";
48"P5E_CPU1_P0_TX_BUF_C_DN<8>";
49"P5E_CPU1_P0_TX_BUF_C_DN<9>";
50"P5E_CPU1_P0_TX_BUF_C_DP<9>";
51"P5E_CPU1_P0_TX_BUF_C_DN<10>";
52"P5E_CPU1_P0_TX_BUF_C_DP<10>";
53"P5E_CPU1_P0_TX_BUF_C_DP<11>";
54"P5E_CPU1_P0_TX_BUF_C_DN<11>";
55"P5E_CPU1_P0_TX_BUF_C_DN<12>";
56"P5E_CPU1_P0_TX_BUF_DP<9>";
57"P5E_CPU1_P0_TX_BUF_DP<10>";
58"P5E_CPU1_P0_TX_BUF_DP<11>";
59"P5E_CPU1_P0_TX_BUF_DP<12>";
60"P5E_CPU1_P0_TX_BUF_C_DP<13>";
61"P5E_CPU1_P0_TX_BUF_DP<13>";
62"P5E_CPU1_P0_TX_BUF_C_DN<13>";
63"P5E_CPU1_P0_TX_BUF_C_DP<14>";
64"P5E_CPU1_P0_TX_BUF_C_DN<14>";
65"P5E_CPU1_P0_TX_BUF_C_DP<15>";
66"P5E_CPU1_P0_TX_BUF_C_DN<15>";
67"P5E_CPU1_P0_TX_BUF_DP<14>";
68"P5E_CPU1_P0_TX_BUF_DP<15>";
69"P5E_CPU1_P0_TX_BUF_DN<8>";
70"P5E_CPU1_P0_TX_BUF_DN<9>";
71"P5E_CPU1_P0_TX_BUF_DN<10>";
72"P5E_CPU1_P0_TX_BUF_DN<11>";
73"P5E_CPU1_P0_TX_BUF_DN<12>";
74"P5E_CPU1_P0_TX_BUF_DN<13>";
75"P5E_CPU1_P0_TX_BUF_DN<14>";
76"P5E_CPU1_P0_TX_BUF_DN<15>";
77"P5E_CPU1_P0_TX_BUF_C_DP<4>";
78"P5E_CPU1_P0_TX_BUF_C_DP<0>";
79"P5E_CPU1_P0_TX_BUF_C_DN<0>";
80"P5E_CPU1_P0_TX_BUF_C_DP<1>";
81"P5E_CPU1_P0_TX_BUF_C_DN<1>";
82"P5E_CPU1_P0_TX_BUF_C_DP<2>";
83"P5E_CPU1_P0_TX_BUF_C_DN<2>";
84"P5E_CPU1_P0_TX_BUF_C_DP<3>";
85"P5E_CPU1_P0_TX_BUF_DP<0>";
86"P5E_CPU1_P0_TX_BUF_DP<1>";
87"P5E_CPU1_P0_TX_BUF_DP<2>";
88"P5E_CPU1_P0_TX_BUF_DP<3>";
89"P5E_CPU1_P0_TX_BUF_DP<4>";
90"P5E_CPU1_P0_TX_BUF_DN<0>";
91"P5E_CPU1_P0_TX_BUF_DN<2>";
92"P5E_CPU1_P0_TX_BUF_DN<3>";
93"P5E_CPU1_P0_TX_BUF_C_DP<5>";
94"P5E_CPU1_P0_TX_BUF_C_DN<5>";
95"P5E_CPU1_P0_TX_BUF_C_DN<6>";
96"P5E_CPU1_P0_TX_BUF_C_DP<6>";
97"P5E_CPU1_P0_TX_BUF_C_DN<7>";
98"P5E_CPU1_P0_TX_BUF_C_DP<7>";
99"P5E_CPU1_P0_TX_BUF_DP<5>";
100"P5E_CPU1_P0_TX_BUF_DP<6>";
101"P5E_CPU1_P0_TX_BUF_DP<7>";
102"P5E_CPU1_P0_TX_BUF_DN<4>";
103"P5E_CPU1_P0_TX_BUF_DN<5>";
104"P5E_CPU1_P0_TX_BUF_DN<6>";
105"P5E_CPU1_P0_TX_BUF_DN<7>";
106"P5E_CPU1_P0_TX_BUF_C_DN<4>";
107"P5E_CPU1_P0_TX_BUF_C_DN<3>";
108"P5E_CPU1_P0_TX_BUF_DN<1>";
%"TAP"
"1","(-3075,825)","2","standard","I10";
;
CDS_LIB"standard"
BODY_TYPE"PLUMBING"
HDL_TAP"TRUE";
"B \NAC \NWC"3;
"S \NAC"
BN"6"100;
%"TAP"
"1","(-7675,1850)","2","standard","I100";
;
CDS_LIB"standard"
BODY_TYPE"PLUMBING"
HDL_TAP"TRUE";
"B \NAC \NWC"6;
"S \NAC"
BN"9"56;
%"TAP"
"1","(-7675,2050)","2","standard","I101";
;
CDS_LIB"standard"
BODY_TYPE"PLUMBING"
HDL_TAP"TRUE";
"B \NAC \NWC"6;
"S \NAC"
BN"8"47;
%"Q_CAP_DIFFBUS"
"2","(-6950,1850)","2","pure_quanta","I102";
;
LOCATION"C6647"
$SEC"1"
CDS_SEC"1"
VALUE"DIFF BUS_0.22UF"
CDS_LMAN_SYM_OUTLINE"-25,50,25,-50"
CDS_LIB"pure_quanta"
PIN_NAMES_ROTATE"TRUE"
VOLTAGE"6.3V"
MATERIAL"X6S"
PACK_TYPE"C0201"
TOLERANCE"20%"
PART_NUMBER"SP_CH4221MEE01"
LOCATION"C6647";
"2"
$PN"2"56;
"1"
$PN"1"50;
%"Q_CAP_DIFFBUS"
"2","(-6950,1800)","2","pure_quanta","I103";
;
LOCATION"C6648"
$SEC"1"
CDS_SEC"1"
VALUE"DIFF BUS_0.22UF"
CDS_LMAN_SYM_OUTLINE"-25,50,25,-50"
CDS_LIB"pure_quanta"
PIN_NAMES_ROTATE"TRUE"
VOLTAGE"6.3V"
MATERIAL"X6S"
PACK_TYPE"C0201"
TOLERANCE"20%"
PART_NUMBER"SP_CH4221MEE01"
LOCATION"C6648";
"2"
$PN"2"70;
"1"
$PN"1"49;
%"Q_CAP_DIFFBUS"
"2","(-6950,2000)","2","pure_quanta","I104";
;
LOCATION"C6646"
$SEC"1"
CDS_SEC"1"
VALUE"DIFF BUS_0.22UF"
CDS_LMAN_SYM_OUTLINE"-25,50,25,-50"
CDS_LIB"pure_quanta"
PIN_NAMES_ROTATE"TRUE"
VOLTAGE"6.3V"
MATERIAL"X6S"
PACK_TYPE"C0201"
TOLERANCE"20%"
PART_NUMBER"SP_CH4221MEE01"
LOCATION"C6646";
"2"
$PN"2"69;
"1"
$PN"1"48;
%"Q_CAP_DIFFBUS"
"2","(-6950,2050)","2","pure_quanta","I105";
;
LOCATION"C6645"
$SEC"1"
CDS_SEC"1"
VOLTAGE"6.3V"
MATERIAL"X6S"
TOLERANCE"20%"
PACK_TYPE"C0201"
VALUE"DIFF BUS_0.22UF"
CDS_LIB"pure_quanta"
CDS_LMAN_SYM_OUTLINE"-25,50,25,-50"
PIN_NAMES_ROTATE"TRUE"
PART_NUMBER"SP_CH4221MEE01"
LOCATION"C6645";
"2"
$PN"2"47;
"1"
$PN"1"46;
%"TAP"
"1","(-6400,650)","0","standard","I106";
;
CDS_LIB"standard"
BODY_TYPE"PLUMBING"
HDL_TAP"TRUE";
"B \NAC \NWC"8;
"S \NAC"
BN"15"65;
%"TAP"
"1","(-6200,600)","0","standard","I107";
;
CDS_LIB"standard"
BODY_TYPE"PLUMBING"
HDL_TAP"TRUE";
"B \NAC \NWC"7;
"S \NAC"
BN"15"66;
%"TAP"
"1","(-6400,850)","0","standard","I108";
;
CDS_LIB"standard"
BODY_TYPE"PLUMBING"
HDL_TAP"TRUE";
"B \NAC \NWC"8;
"S \NAC"
BN"14"63;
%"TAP"
"1","(-6400,1050)","0","standard","I109";
;
CDS_LIB"standard"
BODY_TYPE"PLUMBING"
HDL_TAP"TRUE";
"B \NAC \NWC"8;
"S \NAC"
BN"13"60;
%"TAP"
"1","(-3075,1025)","2","standard","I11";
;
CDS_LIB"standard"
BODY_TYPE"PLUMBING"
HDL_TAP"TRUE";
"B \NAC \NWC"3;
"S \NAC"
BN"5"99;
%"TAP"
"1","(-6200,800)","0","standard","I110";
;
CDS_LIB"standard"
BODY_TYPE"PLUMBING"
HDL_TAP"TRUE";
"B \NAC \NWC"7;
"S \NAC"
BN"14"64;
%"TAP"
"1","(-6200,1000)","0","standard","I111";
;
CDS_LIB"standard"
BODY_TYPE"PLUMBING"
HDL_TAP"TRUE";
"B \NAC \NWC"7;
"S \NAC"
BN"13"62;
%"TAP"
"1","(-6200,1200)","0","standard","I112";
;
CDS_LIB"standard"
BODY_TYPE"PLUMBING"
HDL_TAP"TRUE";
"B \NAC \NWC"7;
"S \NAC"
BN"12"55;
%"TAP"
"1","(-6400,1250)","0","standard","I113";
;
CDS_LIB"standard"
BODY_TYPE"PLUMBING"
HDL_TAP"TRUE";
"B \NAC \NWC"8;
"S \NAC"
BN"12"45;
%"TAP"
"1","(-6400,1450)","0","standard","I114";
;
CDS_LIB"standard"
BODY_TYPE"PLUMBING"
HDL_TAP"TRUE";
"B \NAC \NWC"8;
"S \NAC"
BN"11"53;
%"TAP"
"1","(-6400,1650)","0","standard","I115";
;
CDS_LIB"standard"
BODY_TYPE"PLUMBING"
HDL_TAP"TRUE";
"B \NAC \NWC"8;
"S \NAC"
BN"10"52;
%"TAP"
"1","(-6200,1400)","0","standard","I116";
;
CDS_LIB"standard"
BODY_TYPE"PLUMBING"
HDL_TAP"TRUE";
"B \NAC \NWC"7;
"S \NAC"
BN"11"54;
%"TAP"
"1","(-6200,1600)","0","standard","I117";
;
CDS_LIB"standard"
BODY_TYPE"PLUMBING"
HDL_TAP"TRUE";
"B \NAC \NWC"7;
"S \NAC"
BN"10"51;
%"TAP"
"1","(-6400,1850)","0","standard","I118";
;
CDS_LIB"standard"
BODY_TYPE"PLUMBING"
HDL_TAP"TRUE";
"B \NAC \NWC"8;
"S \NAC"
BN"9"50;
%"TAP"
"1","(-6400,2050)","0","standard","I119";
;
CDS_LIB"standard"
BODY_TYPE"PLUMBING"
HDL_TAP"TRUE";
"B \NAC \NWC"8;
"S \NAC"
BN"8"46;
%"TAP"
"1","(-3075,1225)","2","standard","I12";
;
CDS_LIB"standard"
BODY_TYPE"PLUMBING"
HDL_TAP"TRUE";
"B \NAC \NWC"3;
"S \NAC"
BN"4"89;
%"TAP"
"1","(-6200,1800)","0","standard","I120";
;
CDS_LIB"standard"
BODY_TYPE"PLUMBING"
HDL_TAP"TRUE";
"B \NAC \NWC"7;
"S \NAC"
BN"9"49;
%"TAP"
"1","(-6200,2000)","0","standard","I121";
;
CDS_LIB"standard"
BODY_TYPE"PLUMBING"
HDL_TAP"TRUE";
"B \NAC \NWC"7;
"S \NAC"
BN"8"48;
%"TAP"
"1","(-1800,3250)","0","standard","I122";
;
CDS_LIB"standard"
BODY_TYPE"PLUMBING"
HDL_TAP"TRUE";
"B \NAC \NWC"11;
"S \NAC"
BN"0"31;
%"TAP"
"1","(-1600,3150)","0","standard","I123";
;
CDS_LIB"standard"
BODY_TYPE"PLUMBING"
HDL_TAP"TRUE";
"B \NAC \NWC"12;
"S \NAC"
BN"0"15;
%"TAP"
"1","(-1800,3600)","0","standard","I124";
;
CDS_LIB"standard"
BODY_TYPE"PLUMBING"
HDL_TAP"TRUE";
"B \NAC \NWC"11;
"S \NAC"
BN"1"16;
%"TAP"
"1","(-1600,3500)","0","standard","I125";
;
CDS_LIB"standard"
BODY_TYPE"PLUMBING"
HDL_TAP"TRUE";
"B \NAC \NWC"12;
"S \NAC"
BN"1"32;
%"TAP"
"1","(-1800,3950)","0","standard","I128";
;
CDS_LIB"standard"
BODY_TYPE"PLUMBING"
HDL_TAP"TRUE";
"B \NAC \NWC"11;
"S \NAC"
BN"2"17;
%"TAP"
"1","(-1600,3850)","0","standard","I129";
;
CDS_LIB"standard"
BODY_TYPE"PLUMBING"
HDL_TAP"TRUE";
"B \NAC \NWC"12;
"S \NAC"
BN"2"18;
%"TAP"
"1","(-3075,1425)","2","standard","I13";
;
CDS_LIB"standard"
BODY_TYPE"PLUMBING"
HDL_TAP"TRUE";
"B \NAC \NWC"3;
"S \NAC"
BN"3"88;
%"TAP"
"1","(-1600,4200)","0","standard","I130";
;
CDS_LIB"standard"
BODY_TYPE"PLUMBING"
HDL_TAP"TRUE";
"B \NAC \NWC"12;
"S \NAC"
BN"3"33;
%"TAP"
"1","(-1800,4300)","0","standard","I131";
;
CDS_LIB"standard"
BODY_TYPE"PLUMBING"
HDL_TAP"TRUE";
"B \NAC \NWC"11;
"S \NAC"
BN"3"34;
%"TAP"
"1","(-1800,4650)","0","standard","I132";
;
CDS_LIB"standard"
BODY_TYPE"PLUMBING"
HDL_TAP"TRUE";
"B \NAC \NWC"11;
"S \NAC"
BN"4"19;
%"TAP"
"1","(-1600,4550)","0","standard","I133";
;
CDS_LIB"standard"
BODY_TYPE"PLUMBING"
HDL_TAP"TRUE";
"B \NAC \NWC"12;
"S \NAC"
BN"4"20;
%"TAP"
"1","(-1800,5000)","0","standard","I134";
;
CDS_LIB"standard"
BODY_TYPE"PLUMBING"
HDL_TAP"TRUE";
"B \NAC \NWC"11;
"S \NAC"
BN"5"35;
%"TAP"
"1","(-1600,4900)","0","standard","I135";
;
CDS_LIB"standard"
BODY_TYPE"PLUMBING"
HDL_TAP"TRUE";
"B \NAC \NWC"12;
"S \NAC"
BN"5"21;
%"TAP"
"1","(-1600,5250)","0","standard","I136";
;
CDS_LIB"standard"
BODY_TYPE"PLUMBING"
HDL_TAP"TRUE";
"B \NAC \NWC"12;
"S \NAC"
BN"6"36;
%"TAP"
"1","(-1800,5350)","0","standard","I137";
;
CDS_LIB"standard"
BODY_TYPE"PLUMBING"
HDL_TAP"TRUE";
"B \NAC \NWC"11;
"S \NAC"
BN"6"27;
%"TAP"
"1","(-1800,5700)","0","standard","I138";
;
CDS_LIB"standard"
BODY_TYPE"PLUMBING"
HDL_TAP"TRUE";
"B \NAC \NWC"11;
"S \NAC"
BN"7"38;
%"TAP"
"1","(-1600,5600)","0","standard","I139";
;
CDS_LIB"standard"
BODY_TYPE"PLUMBING"
HDL_TAP"TRUE";
"B \NAC \NWC"12;
"S \NAC"
BN"7"37;
%"TAP"
"1","(-3075,1625)","2","standard","I14";
;
CDS_LIB"standard"
BODY_TYPE"PLUMBING"
HDL_TAP"TRUE";
"B \NAC \NWC"3;
"S \NAC"
BN"2"87;
%"PT5161LRS"
"11","(-2525,4450)","0","pure_quanta","I142";
;
LOCATION"U6014"
$SEC"11"
CDS_SEC"11"
PART_TYPE"SMLF"
VALUE"PT5161LRS"
MATERIAL"IC"
CDS_LIB"pure_quanta"
CDS_LMAN_SYM_OUTLINE"-350,1450,300,-1400"
NEEDS_NO_SIZE"TRUE"
PART_NUMBER"AJ051610U03";
"B_PETN15"
$PN"EW10"15;
"B_PETP15"
$PN"EU7"31;
"B_PETN14"
$PN"EM10"32;
"B_PETP14"
$PN"EK7"16;
"B_PETN13"
$PN"EE10"18;
"B_PETP13"
$PN"EC7"17;
"B_PETN12"
$PN"DV10"33;
"B_PETP12"
$PN"DT7"34;
"B_PETN11"
$PN"DL10"20;
"B_PETP11"
$PN"DJ7"19;
"B_PETN10"
$PN"DD10"21;
"B_PETP10"
$PN"DB7"35;
"B_PETN9"
$PN"CU10"36;
"B_PETP9"
$PN"CR7"27;
"B_PETN8"
$PN"CK10"37;
"B_PETP8"
$PN"CH7"38;
%"Q_CAP_DIFFBUS"
"2","(-2350,575)","2","pure_quanta","I15";
;
LOCATION"C6644"
$SEC"1"
CDS_SEC"1"
VALUE"DIFF BUS_0.22UF"
TOLERANCE"20%"
PACK_TYPE"C0201"
MATERIAL"X6S"
VOLTAGE"6.3V"
PIN_NAMES_ROTATE"TRUE"
CDS_LIB"pure_quanta"
CDS_LMAN_SYM_OUTLINE"-25,50,25,-50"
PART_NUMBER"SP_CH4221MEE01"
LOCATION"C6644";
"2"
$PN"2"105;
"1"
$PN"1"97;
%"Q_CAP_DIFFBUS"
"2","(-2350,625)","2","pure_quanta","I16";
;
LOCATION"C6643"
$SEC"1"
CDS_SEC"1"
VALUE"DIFF BUS_0.22UF"
TOLERANCE"20%"
PACK_TYPE"C0201"
MATERIAL"X6S"
VOLTAGE"6.3V"
PIN_NAMES_ROTATE"TRUE"
CDS_LIB"pure_quanta"
CDS_LMAN_SYM_OUTLINE"-25,50,25,-50"
PART_NUMBER"SP_CH4221MEE01"
LOCATION"C6643";
"2"
$PN"2"101;
"1"
$PN"1"98;
%"TAP"
"1","(-1600,575)","0","standard","I17";
;
CDS_LIB"standard"
BODY_TYPE"PLUMBING"
HDL_TAP"TRUE";
"B \NAC \NWC"2;
"S \NAC"
BN"7"97;
%"Q_CAP_DIFFBUS"
"2","(-2350,825)","2","pure_quanta","I18";
;
LOCATION"C6641"
$SEC"1"
CDS_SEC"1"
VALUE"DIFF BUS_0.22UF"
TOLERANCE"20%"
PACK_TYPE"C0201"
MATERIAL"X6S"
VOLTAGE"6.3V"
PIN_NAMES_ROTATE"TRUE"
CDS_LMAN_SYM_OUTLINE"-25,50,25,-50"
CDS_LIB"pure_quanta"
PART_NUMBER"SP_CH4221MEE01"
LOCATION"C6641";
"2"
$PN"2"100;
"1"
$PN"1"96;
%"Q_CAP_DIFFBUS"
"2","(-2350,775)","2","pure_quanta","I19";
;
LOCATION"C6642"
$SEC"1"
CDS_SEC"1"
VALUE"DIFF BUS_0.22UF"
TOLERANCE"20%"
PACK_TYPE"C0201"
MATERIAL"X6S"
VOLTAGE"6.3V"
PIN_NAMES_ROTATE"TRUE"
CDS_LIB"pure_quanta"
CDS_LMAN_SYM_OUTLINE"-25,50,25,-50"
PART_NUMBER"SP_CH4221MEE01"
LOCATION"C6642";
"2"
$PN"2"104;
"1"
$PN"1"95;
%"Q_CAP_DIFFBUS"
"2","(-2350,1025)","2","pure_quanta","I20";
;
LOCATION"C6639"
$SEC"1"
CDS_SEC"1"
VALUE"DIFF BUS_0.22UF"
TOLERANCE"20%"
PACK_TYPE"C0201"
MATERIAL"X6S"
VOLTAGE"6.3V"
PIN_NAMES_ROTATE"TRUE"
CDS_LIB"pure_quanta"
CDS_LMAN_SYM_OUTLINE"-25,50,25,-50"
PART_NUMBER"SP_CH4221MEE01"
LOCATION"C6639";
"2"
$PN"2"99;
"1"
$PN"1"93;
%"Q_CAP_DIFFBUS"
"2","(-2350,975)","2","pure_quanta","I21";
;
LOCATION"C6640"
$SEC"1"
CDS_SEC"1"
VALUE"DIFF BUS_0.22UF"
TOLERANCE"20%"
PACK_TYPE"C0201"
MATERIAL"X6S"
VOLTAGE"6.3V"
PIN_NAMES_ROTATE"TRUE"
CDS_LIB"pure_quanta"
CDS_LMAN_SYM_OUTLINE"-25,50,25,-50"
PART_NUMBER"SP_CH4221MEE01"
LOCATION"C6640";
"2"
$PN"2"103;
"1"
$PN"1"94;
%"Q_CAP_DIFFBUS"
"2","(-2350,1225)","2","pure_quanta","I22";
;
LOCATION"C6637"
$SEC"1"
CDS_SEC"1"
VALUE"DIFF BUS_0.22UF"
TOLERANCE"20%"
PACK_TYPE"C0201"
MATERIAL"X6S"
VOLTAGE"6.3V"
PIN_NAMES_ROTATE"TRUE"
CDS_LMAN_SYM_OUTLINE"-25,50,25,-50"
CDS_LIB"pure_quanta"
PART_NUMBER"SP_CH4221MEE01"
LOCATION"C6637";
"2"
$PN"2"89;
"1"
$PN"1"77;
%"Q_CAP_DIFFBUS"
"2","(-2350,1175)","2","pure_quanta","I23";
;
LOCATION"C6638"
$SEC"1"
CDS_SEC"1"
VALUE"DIFF BUS_0.22UF"
TOLERANCE"20%"
PACK_TYPE"C0201"
MATERIAL"X6S"
VOLTAGE"6.3V"
PIN_NAMES_ROTATE"TRUE"
CDS_LMAN_SYM_OUTLINE"-25,50,25,-50"
CDS_LIB"pure_quanta"
PART_NUMBER"SP_CH4221MEE01"
LOCATION"C6638";
"2"
$PN"2"102;
"1"
$PN"1"106;
%"Q_CAP_DIFFBUS"
"2","(-2350,1375)","2","pure_quanta","I24";
;
LOCATION"C6636"
$SEC"1"
CDS_SEC"1"
VALUE"DIFF BUS_0.22UF"
TOLERANCE"20%"
PACK_TYPE"C0201"
MATERIAL"X6S"
VOLTAGE"6.3V"
PIN_NAMES_ROTATE"TRUE"
CDS_LIB"pure_quanta"
CDS_LMAN_SYM_OUTLINE"-25,50,25,-50"
PART_NUMBER"SP_CH4221MEE01"
LOCATION"C6636";
"2"
$PN"2"92;
"1"
$PN"1"107;
%"Q_CAP_DIFFBUS"
"2","(-2350,1425)","2","pure_quanta","I25";
;
LOCATION"C6635"
$SEC"1"
CDS_SEC"1"
VALUE"DIFF BUS_0.22UF"
TOLERANCE"20%"
PACK_TYPE"C0201"
MATERIAL"X6S"
VOLTAGE"6.3V"
PIN_NAMES_ROTATE"TRUE"
CDS_LIB"pure_quanta"
CDS_LMAN_SYM_OUTLINE"-25,50,25,-50"
PART_NUMBER"SP_CH4221MEE01"
LOCATION"C6635";
"2"
$PN"2"88;
"1"
$PN"1"84;
%"Q_CAP_DIFFBUS"
"2","(-2350,1575)","2","pure_quanta","I26";
;
LOCATION"C6634"
$SEC"1"
CDS_SEC"1"
VALUE"DIFF BUS_0.22UF"
TOLERANCE"20%"
PACK_TYPE"C0201"
MATERIAL"X6S"
VOLTAGE"6.3V"
PIN_NAMES_ROTATE"TRUE"
CDS_LIB"pure_quanta"
CDS_LMAN_SYM_OUTLINE"-25,50,25,-50"
PART_NUMBER"SP_CH4221MEE01"
LOCATION"C6634";
"2"
$PN"2"91;
"1"
$PN"1"83;
%"Q_CAP_DIFFBUS"
"2","(-2350,1625)","2","pure_quanta","I27";
;
LOCATION"C6633"
$SEC"1"
CDS_SEC"1"
VALUE"DIFF BUS_0.22UF"
TOLERANCE"20%"
PACK_TYPE"C0201"
MATERIAL"X6S"
VOLTAGE"6.3V"
PIN_NAMES_ROTATE"TRUE"
CDS_LIB"pure_quanta"
CDS_LMAN_SYM_OUTLINE"-25,50,25,-50"
PART_NUMBER"SP_CH4221MEE01"
LOCATION"C6633";
"2"
$PN"2"87;
"1"
$PN"1"82;
%"TAP"
"1","(-1800,625)","0","standard","I28";
;
CDS_LIB"standard"
BODY_TYPE"PLUMBING"
HDL_TAP"TRUE";
"B \NAC \NWC"4;
"S \NAC"
BN"7"98;
%"TAP"
"1","(-1800,1025)","0","standard","I29";
;
CDS_LIB"standard"
BODY_TYPE"PLUMBING"
HDL_TAP"TRUE";
"B \NAC \NWC"4;
"S \NAC"
BN"5"93;
%"TAP"
"1","(-3325,575)","2","standard","I3";
;
CDS_LIB"standard"
BODY_TYPE"PLUMBING"
HDL_TAP"TRUE";
"B \NAC \NWC"1;
"S \NAC"
BN"7"105;
%"TAP"
"1","(-1800,825)","0","standard","I30";
;
CDS_LIB"standard"
BODY_TYPE"PLUMBING"
HDL_TAP"TRUE";
"B \NAC \NWC"4;
"S \NAC"
BN"6"96;
%"TAP"
"1","(-1600,775)","0","standard","I31";
;
CDS_LIB"standard"
BODY_TYPE"PLUMBING"
HDL_TAP"TRUE";
"B \NAC \NWC"2;
"S \NAC"
BN"6"95;
%"TAP"
"1","(-1600,975)","0","standard","I32";
;
CDS_LIB"standard"
BODY_TYPE"PLUMBING"
HDL_TAP"TRUE";
"B \NAC \NWC"2;
"S \NAC"
BN"5"94;
%"TAP"
"1","(-1800,1425)","0","standard","I33";
;
CDS_LIB"standard"
BODY_TYPE"PLUMBING"
HDL_TAP"TRUE";
"B \NAC \NWC"4;
"S \NAC"
BN"3"84;
%"TAP"
"1","(-1800,1625)","0","standard","I34";
;
CDS_LIB"standard"
BODY_TYPE"PLUMBING"
HDL_TAP"TRUE";
"B \NAC \NWC"4;
"S \NAC"
BN"2"82;
%"TAP"
"1","(-1800,1225)","0","standard","I35";
;
CDS_LIB"standard"
BODY_TYPE"PLUMBING"
HDL_TAP"TRUE";
"B \NAC \NWC"4;
"S \NAC"
BN"4"77;
%"TAP"
"1","(-1600,1375)","0","standard","I36";
;
CDS_LIB"standard"
BODY_TYPE"PLUMBING"
HDL_TAP"TRUE";
"B \NAC \NWC"2;
"S \NAC"
BN"3"107;
%"TAP"
"1","(-1600,1175)","0","standard","I37";
;
CDS_LIB"standard"
BODY_TYPE"PLUMBING"
HDL_TAP"TRUE";
"B \NAC \NWC"2;
"S \NAC"
BN"4"106;
%"TAP"
"1","(-1600,1575)","0","standard","I38";
;
CDS_LIB"standard"
BODY_TYPE"PLUMBING"
HDL_TAP"TRUE";
"B \NAC \NWC"2;
"S \NAC"
BN"2"83;
%"TAP"
"1","(-3325,1775)","2","standard","I39";
;
CDS_LIB"standard"
BODY_TYPE"PLUMBING"
HDL_TAP"TRUE";
"B \NAC \NWC"1;
"S \NAC"
BN"1"108;
%"TAP"
"1","(-3325,775)","2","standard","I4";
;
CDS_LIB"standard"
BODY_TYPE"PLUMBING"
HDL_TAP"TRUE";
"B \NAC \NWC"1;
"S \NAC"
BN"6"104;
%"TAP"
"1","(-3325,1975)","2","standard","I40";
;
CDS_LIB"standard"
BODY_TYPE"PLUMBING"
HDL_TAP"TRUE";
"B \NAC \NWC"1;
"S \NAC"
BN"0"90;
%"TAP"
"1","(-3075,1825)","2","standard","I41";
;
CDS_LIB"standard"
BODY_TYPE"PLUMBING"
HDL_TAP"TRUE";
"B \NAC \NWC"3;
"S \NAC"
BN"1"86;
%"TAP"
"1","(-3075,2025)","2","standard","I42";
;
CDS_LIB"standard"
BODY_TYPE"PLUMBING"
HDL_TAP"TRUE";
"B \NAC \NWC"3;
"S \NAC"
BN"0"85;
%"PT5161LRS"
"10","(-7700,4475)","0","pure_quanta","I43";
;
LOCATION"U6014"
$SEC"10"
CDS_SEC"10"
PART_TYPE"SMLF"
VALUE"PT5161LRS"
MATERIAL"IC"
NEEDS_NO_SIZE"TRUE"
CDS_LMAN_SYM_OUTLINE"-350,1450,300,-1400"
CDS_LIB"pure_quanta"
PART_NUMBER"AJ051610U03";
"B_PETN7"
$PN"CC10"30;
"B_PETP7"
$PN"CA7"29;
"B_PETN6"
$PN"BT10"39;
"B_PETP6"
$PN"BP7"40;
"B_PETN5"
$PN"BJ10"26;
"B_PETP5"
$PN"BG7"24;
"B_PETN4"
$PN"BB10"28;
"B_PETP4"
$PN"AY7"22;
"B_PETN3"
$PN"AR10"14;
"B_PETP3"
$PN"AN7"23;
"B_PETN2"
$PN"AH10"13;
"B_PETP2"
$PN"AF7"25;
"B_PETN1"
$PN"AA10"42;
"B_PETP1"
$PN"W7"43;
"B_PETN0"
$PN"P10"44;
"B_PETP0"
$PN"M7"41;
%"Q_CAP_DIFFBUS"
"2","(-2350,1775)","2","pure_quanta","I44";
;
LOCATION"C6632"
$SEC"1"
CDS_SEC"1"
VALUE"DIFF BUS_0.22UF"
TOLERANCE"20%"
PACK_TYPE"C0201"
MATERIAL"X6S"
VOLTAGE"6.3V"
PIN_NAMES_ROTATE"TRUE"
CDS_LIB"pure_quanta"
CDS_LMAN_SYM_OUTLINE"-25,50,25,-50"
PART_NUMBER"SP_CH4221MEE01"
LOCATION"C6632";
"2"
$PN"2"108;
"1"
$PN"1"81;
%"Q_CAP_DIFFBUS"
"2","(-2350,1825)","2","pure_quanta","I45";
;
LOCATION"C6631"
$SEC"1"
CDS_SEC"1"
VALUE"DIFF BUS_0.22UF"
TOLERANCE"20%"
PACK_TYPE"C0201"
MATERIAL"X6S"
VOLTAGE"6.3V"
PIN_NAMES_ROTATE"TRUE"
CDS_LIB"pure_quanta"
CDS_LMAN_SYM_OUTLINE"-25,50,25,-50"
PART_NUMBER"SP_CH4221MEE01"
LOCATION"C6631";
"2"
$PN"2"86;
"1"
$PN"1"80;
%"Q_CAP_DIFFBUS"
"2","(-2350,2025)","2","pure_quanta","I46";
;
LOCATION"C6629"
$SEC"1"
CDS_SEC"1"
MATERIAL"X6S"
TOLERANCE"20%"
VOLTAGE"6.3V"
VALUE"DIFF BUS_0.22UF"
PACK_TYPE"C0201"
PIN_NAMES_ROTATE"TRUE"
CDS_LMAN_SYM_OUTLINE"-25,50,25,-50"
CDS_LIB"pure_quanta"
PART_NUMBER"SP_CH4221MEE01"
LOCATION"C6629";
"2"
$PN"2"85;
"1"
$PN"1"78;
%"Q_CAP_DIFFBUS"
"2","(-2350,1975)","2","pure_quanta","I47";
;
LOCATION"C6630"
$SEC"1"
CDS_SEC"1"
VALUE"DIFF BUS_0.22UF"
TOLERANCE"20%"
PACK_TYPE"C0201"
MATERIAL"X6S"
VOLTAGE"6.3V"
PIN_NAMES_ROTATE"TRUE"
CDS_LIB"pure_quanta"
CDS_LMAN_SYM_OUTLINE"-25,50,25,-50"
PART_NUMBER"SP_CH4221MEE01"
LOCATION"C6630";
"2"
$PN"2"90;
"1"
$PN"1"79;
%"TAP"
"1","(-1800,1825)","0","standard","I48";
;
CDS_LIB"standard"
BODY_TYPE"PLUMBING"
HDL_TAP"TRUE";
"B \NAC \NWC"4;
"S \NAC"
BN"1"80;
%"TAP"
"1","(-1800,2025)","0","standard","I49";
;
CDS_LIB"standard"
BODY_TYPE"PLUMBING"
HDL_TAP"TRUE";
"B \NAC \NWC"4;
"S \NAC"
BN"0"78;
%"TAP"
"1","(-3325,975)","2","standard","I5";
;
CDS_LIB"standard"
BODY_TYPE"PLUMBING"
HDL_TAP"TRUE";
"B \NAC \NWC"1;
"S \NAC"
BN"5"103;
%"TAP"
"1","(-1600,1775)","0","standard","I50";
;
CDS_LIB"standard"
BODY_TYPE"PLUMBING"
HDL_TAP"TRUE";
"B \NAC \NWC"2;
"S \NAC"
BN"1"81;
%"TAP"
"1","(-1600,1975)","0","standard","I51";
;
CDS_LIB"standard"
BODY_TYPE"PLUMBING"
HDL_TAP"TRUE";
"B \NAC \NWC"2;
"S \NAC"
BN"0"79;
%"TAP"
"1","(-6775,3175)","0","standard","I52";
;
CDS_LIB"standard"
BODY_TYPE"PLUMBING"
HDL_TAP"TRUE";
"B \NAC \NWC"9;
"S \NAC"
BN"8"30;
%"TAP"
"1","(-6975,3275)","0","standard","I53";
;
CDS_LIB"standard"
BODY_TYPE"PLUMBING"
HDL_TAP"TRUE";
"B \NAC \NWC"10;
"S \NAC"
BN"8"29;
%"TAP"
"1","(-6775,3525)","0","standard","I54";
;
CDS_LIB"standard"
BODY_TYPE"PLUMBING"
HDL_TAP"TRUE";
"B \NAC \NWC"9;
"S \NAC"
BN"9"39;
%"TAP"
"1","(-6975,3625)","0","standard","I55";
;
CDS_LIB"standard"
BODY_TYPE"PLUMBING"
HDL_TAP"TRUE";
"B \NAC \NWC"10;
"S \NAC"
BN"9"40;
%"TAP"
"1","(-3325,1175)","2","standard","I6";
;
CDS_LIB"standard"
BODY_TYPE"PLUMBING"
HDL_TAP"TRUE";
"B \NAC \NWC"1;
"S \NAC"
BN"4"102;
%"TAP"
"1","(-6775,3875)","0","standard","I60";
;
CDS_LIB"standard"
BODY_TYPE"PLUMBING"
HDL_TAP"TRUE";
"B \NAC \NWC"9;
"S \NAC"
BN"10"26;
%"TAP"
"1","(-6975,3975)","0","standard","I61";
;
CDS_LIB"standard"
BODY_TYPE"PLUMBING"
HDL_TAP"TRUE";
"B \NAC \NWC"10;
"S \NAC"
BN"10"24;
%"TAP"
"1","(-6775,4225)","0","standard","I62";
;
CDS_LIB"standard"
BODY_TYPE"PLUMBING"
HDL_TAP"TRUE";
"B \NAC \NWC"9;
"S \NAC"
BN"11"28;
%"TAP"
"1","(-6975,4325)","0","standard","I63";
;
CDS_LIB"standard"
BODY_TYPE"PLUMBING"
HDL_TAP"TRUE";
"B \NAC \NWC"10;
"S \NAC"
BN"11"22;
%"TAP"
"1","(-6975,4675)","0","standard","I64";
;
CDS_LIB"standard"
BODY_TYPE"PLUMBING"
HDL_TAP"TRUE";
"B \NAC \NWC"10;
"S \NAC"
BN"12"23;
%"TAP"
"1","(-6775,4575)","0","standard","I65";
;
CDS_LIB"standard"
BODY_TYPE"PLUMBING"
HDL_TAP"TRUE";
"B \NAC \NWC"9;
"S \NAC"
BN"12"14;
%"TAP"
"1","(-6775,4925)","0","standard","I66";
;
CDS_LIB"standard"
BODY_TYPE"PLUMBING"
HDL_TAP"TRUE";
"B \NAC \NWC"9;
"S \NAC"
BN"13"13;
%"TAP"
"1","(-6975,5025)","0","standard","I67";
;
CDS_LIB"standard"
BODY_TYPE"PLUMBING"
HDL_TAP"TRUE";
"B \NAC \NWC"10;
"S \NAC"
BN"13"25;
%"TAP"
"1","(-6775,5275)","0","standard","I68";
;
CDS_LIB"standard"
BODY_TYPE"PLUMBING"
HDL_TAP"TRUE";
"B \NAC \NWC"9;
"S \NAC"
BN"14"42;
%"TAP"
"1","(-6975,5375)","0","standard","I69";
;
CDS_LIB"standard"
BODY_TYPE"PLUMBING"
HDL_TAP"TRUE";
"B \NAC \NWC"10;
"S \NAC"
BN"14"43;
%"TAP"
"1","(-3325,1375)","2","standard","I7";
;
CDS_LIB"standard"
BODY_TYPE"PLUMBING"
HDL_TAP"TRUE";
"B \NAC \NWC"1;
"S \NAC"
BN"3"92;
%"TAP"
"1","(-6775,5625)","0","standard","I70";
;
CDS_LIB"standard"
BODY_TYPE"PLUMBING"
HDL_TAP"TRUE";
"B \NAC \NWC"9;
"S \NAC"
BN"15"44;
%"TAP"
"1","(-6975,5725)","0","standard","I71";
;
CDS_LIB"standard"
BODY_TYPE"PLUMBING"
HDL_TAP"TRUE";
"B \NAC \NWC"10;
"S \NAC"
BN"15"41;
%"TAP"
"1","(-7925,600)","2","standard","I74";
;
CDS_LIB"standard"
BODY_TYPE"PLUMBING"
HDL_TAP"TRUE";
"B \NAC \NWC"5;
"S \NAC"
BN"15"76;
%"TAP"
"1","(-7675,650)","2","standard","I75";
;
CDS_LIB"standard"
BODY_TYPE"PLUMBING"
HDL_TAP"TRUE";
"B \NAC \NWC"6;
"S \NAC"
BN"15"68;
%"TAP"
"1","(-7925,800)","2","standard","I76";
;
CDS_LIB"standard"
BODY_TYPE"PLUMBING"
HDL_TAP"TRUE";
"B \NAC \NWC"5;
"S \NAC"
BN"14"75;
%"TAP"
"1","(-7925,1000)","2","standard","I77";
;
CDS_LIB"standard"
BODY_TYPE"PLUMBING"
HDL_TAP"TRUE";
"B \NAC \NWC"5;
"S \NAC"
BN"13"74;
%"TAP"
"1","(-7925,1200)","2","standard","I78";
;
CDS_LIB"standard"
BODY_TYPE"PLUMBING"
HDL_TAP"TRUE";
"B \NAC \NWC"5;
"S \NAC"
BN"12"73;
%"TAP"
"1","(-7675,850)","2","standard","I79";
;
CDS_LIB"standard"
BODY_TYPE"PLUMBING"
HDL_TAP"TRUE";
"B \NAC \NWC"6;
"S \NAC"
BN"14"67;
%"TAP"
"1","(-3325,1575)","2","standard","I8";
;
CDS_LIB"standard"
BODY_TYPE"PLUMBING"
HDL_TAP"TRUE";
"B \NAC \NWC"1;
"S \NAC"
BN"2"91;
%"TAP"
"1","(-7675,1050)","2","standard","I80";
;
CDS_LIB"standard"
BODY_TYPE"PLUMBING"
HDL_TAP"TRUE";
"B \NAC \NWC"6;
"S \NAC"
BN"13"61;
%"TAP"
"1","(-7925,1400)","2","standard","I81";
;
CDS_LIB"standard"
BODY_TYPE"PLUMBING"
HDL_TAP"TRUE";
"B \NAC \NWC"5;
"S \NAC"
BN"11"72;
%"TAP"
"1","(-7925,1600)","2","standard","I82";
;
CDS_LIB"standard"
BODY_TYPE"PLUMBING"
HDL_TAP"TRUE";
"B \NAC \NWC"5;
"S \NAC"
BN"10"71;
%"TAP"
"1","(-7675,1450)","2","standard","I83";
;
CDS_LIB"standard"
BODY_TYPE"PLUMBING"
HDL_TAP"TRUE";
"B \NAC \NWC"6;
"S \NAC"
BN"11"58;
%"TAP"
"1","(-7675,1250)","2","standard","I84";
;
CDS_LIB"standard"
BODY_TYPE"PLUMBING"
HDL_TAP"TRUE";
"B \NAC \NWC"6;
"S \NAC"
BN"12"59;
%"TAP"
"1","(-7675,1650)","2","standard","I85";
;
CDS_LIB"standard"
BODY_TYPE"PLUMBING"
HDL_TAP"TRUE";
"B \NAC \NWC"6;
"S \NAC"
BN"10"57;
%"Q_CAP_DIFFBUS"
"2","(-6950,600)","2","pure_quanta","I86";
;
LOCATION"C6660"
$SEC"1"
CDS_SEC"1"
VALUE"DIFF BUS_0.22UF"
CDS_LMAN_SYM_OUTLINE"-25,50,25,-50"
CDS_LIB"pure_quanta"
PIN_NAMES_ROTATE"TRUE"
VOLTAGE"6.3V"
MATERIAL"X6S"
PACK_TYPE"C0201"
TOLERANCE"20%"
PART_NUMBER"SP_CH4221MEE01"
LOCATION"C6660";
"2"
$PN"2"76;
"1"
$PN"1"66;
%"Q_CAP_DIFFBUS"
"2","(-6950,650)","2","pure_quanta","I87";
;
LOCATION"C6659"
$SEC"1"
CDS_SEC"1"
VALUE"DIFF BUS_0.22UF"
CDS_LMAN_SYM_OUTLINE"-25,50,25,-50"
CDS_LIB"pure_quanta"
PIN_NAMES_ROTATE"TRUE"
VOLTAGE"6.3V"
MATERIAL"X6S"
PACK_TYPE"C0201"
TOLERANCE"20%"
PART_NUMBER"SP_CH4221MEE01"
LOCATION"C6659";
"2"
$PN"2"68;
"1"
$PN"1"65;
%"Q_CAP_DIFFBUS"
"2","(-6950,800)","2","pure_quanta","I88";
;
LOCATION"C6658"
$SEC"1"
CDS_SEC"1"
VALUE"DIFF BUS_0.22UF"
CDS_LMAN_SYM_OUTLINE"-25,50,25,-50"
CDS_LIB"pure_quanta"
PIN_NAMES_ROTATE"TRUE"
VOLTAGE"6.3V"
MATERIAL"X6S"
PACK_TYPE"C0201"
TOLERANCE"20%"
PART_NUMBER"SP_CH4221MEE01"
LOCATION"C6658";
"2"
$PN"2"75;
"1"
$PN"1"64;
%"Q_CAP_DIFFBUS"
"2","(-6950,850)","2","pure_quanta","I89";
;
LOCATION"C6657"
$SEC"1"
CDS_SEC"1"
VALUE"DIFF BUS_0.22UF"
CDS_LIB"pure_quanta"
CDS_LMAN_SYM_OUTLINE"-25,50,25,-50"
PIN_NAMES_ROTATE"TRUE"
VOLTAGE"6.3V"
MATERIAL"X6S"
PACK_TYPE"C0201"
TOLERANCE"20%"
PART_NUMBER"SP_CH4221MEE01"
LOCATION"C6657";
"2"
$PN"2"67;
"1"
$PN"1"63;
%"TAP"
"1","(-3075,625)","2","standard","I9";
;
CDS_LIB"standard"
BODY_TYPE"PLUMBING"
HDL_TAP"TRUE";
"B \NAC \NWC"3;
"S \NAC"
BN"7"101;
%"Q_CAP_DIFFBUS"
"2","(-6950,1000)","2","pure_quanta","I90";
;
LOCATION"C6656"
$SEC"1"
CDS_SEC"1"
VALUE"DIFF BUS_0.22UF"
CDS_LMAN_SYM_OUTLINE"-25,50,25,-50"
CDS_LIB"pure_quanta"
PIN_NAMES_ROTATE"TRUE"
VOLTAGE"6.3V"
MATERIAL"X6S"
PACK_TYPE"C0201"
TOLERANCE"20%"
PART_NUMBER"SP_CH4221MEE01"
LOCATION"C6656";
"2"
$PN"2"74;
"1"
$PN"1"62;
%"Q_CAP_DIFFBUS"
"2","(-6950,1050)","2","pure_quanta","I91";
;
LOCATION"C6655"
$SEC"1"
CDS_SEC"1"
VALUE"DIFF BUS_0.22UF"
CDS_LMAN_SYM_OUTLINE"-25,50,25,-50"
CDS_LIB"pure_quanta"
PIN_NAMES_ROTATE"TRUE"
VOLTAGE"6.3V"
MATERIAL"X6S"
PACK_TYPE"C0201"
TOLERANCE"20%"
PART_NUMBER"SP_CH4221MEE01"
LOCATION"C6655";
"2"
$PN"2"61;
"1"
$PN"1"60;
%"Q_CAP_DIFFBUS"
"2","(-6950,1200)","2","pure_quanta","I92";
;
LOCATION"C6654"
$SEC"1"
CDS_SEC"1"
VALUE"DIFF BUS_0.22UF"
CDS_LIB"pure_quanta"
CDS_LMAN_SYM_OUTLINE"-25,50,25,-50"
PIN_NAMES_ROTATE"TRUE"
VOLTAGE"6.3V"
MATERIAL"X6S"
PACK_TYPE"C0201"
TOLERANCE"20%"
PART_NUMBER"SP_CH4221MEE01"
LOCATION"C6654";
"2"
$PN"2"73;
"1"
$PN"1"55;
%"Q_CAP_DIFFBUS"
"2","(-6950,1250)","2","pure_quanta","I93";
;
LOCATION"C6653"
$SEC"1"
CDS_SEC"1"
VALUE"DIFF BUS_0.22UF"
CDS_LIB"pure_quanta"
CDS_LMAN_SYM_OUTLINE"-25,50,25,-50"
PIN_NAMES_ROTATE"TRUE"
VOLTAGE"6.3V"
MATERIAL"X6S"
PACK_TYPE"C0201"
TOLERANCE"20%"
PART_NUMBER"SP_CH4221MEE01"
LOCATION"C6653";
"2"
$PN"2"59;
"1"
$PN"1"45;
%"Q_CAP_DIFFBUS"
"2","(-6950,1400)","2","pure_quanta","I94";
;
LOCATION"C6652"
$SEC"1"
CDS_SEC"1"
VALUE"DIFF BUS_0.22UF"
CDS_LMAN_SYM_OUTLINE"-25,50,25,-50"
CDS_LIB"pure_quanta"
PIN_NAMES_ROTATE"TRUE"
VOLTAGE"6.3V"
MATERIAL"X6S"
PACK_TYPE"C0201"
TOLERANCE"20%"
PART_NUMBER"SP_CH4221MEE01"
LOCATION"C6652";
"2"
$PN"2"72;
"1"
$PN"1"54;
%"Q_CAP_DIFFBUS"
"2","(-6950,1450)","2","pure_quanta","I95";
;
LOCATION"C6651"
$SEC"1"
CDS_SEC"1"
VALUE"DIFF BUS_0.22UF"
CDS_LMAN_SYM_OUTLINE"-25,50,25,-50"
CDS_LIB"pure_quanta"
PIN_NAMES_ROTATE"TRUE"
VOLTAGE"6.3V"
MATERIAL"X6S"
PACK_TYPE"C0201"
TOLERANCE"20%"
PART_NUMBER"SP_CH4221MEE01"
LOCATION"C6651";
"2"
$PN"2"58;
"1"
$PN"1"53;
%"Q_CAP_DIFFBUS"
"2","(-6950,1650)","2","pure_quanta","I96";
;
LOCATION"C6649"
$SEC"1"
CDS_SEC"1"
VALUE"DIFF BUS_0.22UF"
CDS_LMAN_SYM_OUTLINE"-25,50,25,-50"
CDS_LIB"pure_quanta"
PIN_NAMES_ROTATE"TRUE"
VOLTAGE"6.3V"
MATERIAL"X6S"
PACK_TYPE"C0201"
TOLERANCE"20%"
PART_NUMBER"SP_CH4221MEE01"
LOCATION"C6649";
"2"
$PN"2"57;
"1"
$PN"1"52;
%"Q_CAP_DIFFBUS"
"2","(-6950,1600)","2","pure_quanta","I97";
;
LOCATION"C6650"
$SEC"1"
CDS_SEC"1"
VALUE"DIFF BUS_0.22UF"
CDS_LMAN_SYM_OUTLINE"-25,50,25,-50"
CDS_LIB"pure_quanta"
PIN_NAMES_ROTATE"TRUE"
VOLTAGE"6.3V"
MATERIAL"X6S"
PACK_TYPE"C0201"
TOLERANCE"20%"
PART_NUMBER"SP_CH4221MEE01"
LOCATION"C6650";
"2"
$PN"2"71;
"1"
$PN"1"51;
%"TAP"
"1","(-7925,1800)","2","standard","I98";
;
CDS_LIB"standard"
BODY_TYPE"PLUMBING"
HDL_TAP"TRUE";
"B \NAC \NWC"5;
"S \NAC"
BN"9"70;
%"TAP"
"1","(-7925,2000)","2","standard","I99";
;
CDS_LIB"standard"
BODY_TYPE"PLUMBING"
HDL_TAP"TRUE";
"B \NAC \NWC"5;
"S \NAC"
BN"8"69;
END.
